FILE_TYPE = CONNECTIVITY;
{Allegro Design Entry HDL 16.6-p007 (v16-6-112F) 10/10/2012}
"PAGE_NUMBER" = 249;
0"NC";
1"GND\g";
2"GND\g";
3"GND\g";
4"P3V3_STBY\g";
5"GND\g";
6"P3V3_STBY\g";
7"GND\g";
8"P3V3_STBY\g";
9"GND\g";
10"GND\g";
11"P3V3_STBY\g";
12"RST_BMC_SRST_N";
13"FM_TPM_PRES_RST";
14"FM_TPM_PRES_RST_N";
15"BMC_TPM_HW_RST";
16"FM_TPM_PRES_N";
17"FM_TPM_PRES_RST_N_R";
18"BMC_TPM_HW_C_RST";
19"VREF_2V2";
%"GND"
"1","(-4550,3625)","0","mstr_symbols","I10";
;
VOLTAGE"0.0V"
BODY_TYPE"PLUMBING"
CDS_LIB"mstr_symbols"
SIZE"1B"
HDL_POWER"GND";
"A\NAC"1;
%"GND"
"1","(-5875,1550)","0","mstr_symbols","I11";
;
VOLTAGE"0.0V"
BODY_TYPE"PLUMBING"
SIZE"1B"
HDL_POWER"GND"
CDS_LIB"mstr_symbols";
"A\NAC"2;
%"RES"
"2","(-6325,1925)","0","mstr_discrete","I12";
;
CDS_SEC"1"
$SEC"1"
CDS_LOCATION"R3W2"
CDS_LIB"mstr_discrete"
ROOM"BMC_DEBUG_HEADER"
MATERIAL"CHIP"
LOCATION"R3W2"
TOLERANCE"1%"
PACK_TYPE"0402"
VALUE"1.00K"
WATTAGE"1/16W"
PART_NUMBER"G21796-026";
"A"
$PN"1"18;
"B"
$PN"2"2;
%"GND"
"1","(-3300,2100)","0","mstr_symbols","I14";
;
VOLTAGE"0.0V"
BODY_TYPE"PLUMBING"
CDS_LIB"mstr_symbols"
SIZE"1B"
HDL_POWER"GND";
"A\NAC"3;
%"LMV331IDCKRG4-GP"
"1","(-3250,2550)","0","w_hdl","I15";
;
CDS_SEC"1"
$SEC"1"
CDS_LOCATION"Q9W4"
CDS_LMAN_SYM_OUTLINE"-100,100,100,-100"
CDS_LIB"w_hdl"
PART_NUMBER"74.00331.A2F"
PACK_TYPE"DISCRET-G"
VALUE"LMV331IDCKRG4-GP"
LOCATION"Q9W4";
"GND"
$PN"2"3;
"VCC"
$PN"5"6;
"OUT"
$PN"4"16;
"-IN"
$PN"3"19;
"+IN"
$PN"1"14;
%"P3V3_STBY"
"1","(-5875,3050)","0","mstr_symbols","I16";
;
VOLTAGE"3.3V"
HDL_POWER"P3V3_STBY"
BODY_TYPE"PLUMBING"
SIZE"1B"
CDS_LIB"mstr_symbols";
"G\NAC"4;
%"RES"
"2","(-5875,2825)","0","mstr_discrete","I17";
;
CDS_SEC"1"
$SEC"1"
CDS_LOCATION"R3W3"
CDS_LIB"mstr_discrete"
ROOM"M_2"
BOM_COST"ST_FLASH"
PART_NUMBER"G21796-016"
WATTAGE"1/16W"
MATERIAL"CHIP"
PACK_TYPE"0402"
VALUE"10.0K"
TOLERANCE"1%"
LOCATION"R3W3";
"A"
$PN"1"4;
"B"
$PN"2"14;
%"GND"
"1","(-3950,3675)","0","mstr_symbols","I18";
;
VOLTAGE"0.0V"
BODY_TYPE"PLUMBING"
HDL_POWER"GND"
SIZE"1B"
CDS_LIB"mstr_symbols";
"A\NAC"5;
%"P3V3_STBY"
"1","(-2975,3150)","0","mstr_symbols","I19";
;
VOLTAGE"3.3V"
SIZE"1B"
BODY_TYPE"PLUMBING"
HDL_POWER"P3V3_STBY"
CDS_LIB"mstr_symbols";
"G\NAC"6;
%"RES"
"2","(-6925,1950)","0","mstr_discrete","I2";
;
CDS_SEC"1"
$SEC"1"
CDS_LOCATION"R3W1"
CDS_LIB"mstr_discrete"
ROOM"BMC_DEBUG_HEADER"
LOCATION"R3W1"
VALUE"1.00K"
PART_NUMBER"G21796-026"
TOLERANCE"1%"
MATERIAL"CHIP"
WATTAGE"1/16W"
PACK_TYPE"0402";
"A"
$PN"1"15;
"B"
$PN"2"9;
%"GND"
"1","(-2975,2750)","0","mstr_symbols","I20";
;
VOLTAGE"0.0V"
BODY_TYPE"PLUMBING"
SIZE"1B"
HDL_POWER"GND"
CDS_LIB"mstr_symbols";
"A\NAC"7;
%"CAP"
"1","(-2975,2950)","0","mstr_discrete","I21";
;
CDS_SEC"1"
$SEC"1"
CDS_LOCATION"C8W2"
BOM_COST"SD_FLASH"
ROOM"M_2"
CDS_LIB"mstr_discrete"
PACK_TYPE"0402LF"
PART_NUMBER"A36096-030"
VALUE"0.1UF"
TOLERANCE"10%"
VOLTAGE"16V"
MATERIAL"X7R"
LOCATION"C8W2";
"A"
$PN"1"6;
"B"
$PN"2"7;
%"P3V3_STBY"
"1","(-4550,4725)","0","mstr_symbols","I24";
;
VOLTAGE"3.3V"
CDS_LIB"mstr_symbols"
SIZE"1B"
BODY_TYPE"PLUMBING"
HDL_POWER"P3V3_STBY";
"G\NAC"8;
%"NPN"
"1","(-4000,4125)","0","mstr_discrete","I26";
;
CDS_SEC"1"
$SEC"1"
CDS_LOCATION"Q9W3"
ROOM"SB"
CDS_LIB"mstr_discrete"
LOCATION"Q9W3"
PACK_TYPE"SM"
VALUE"MMBT3904"
MATERIAL"IC"
PART_NUMBER"C52245-001";
"C"
$PN"3"12;
"E"
$PN"2"5;
"B"
$PN"1"13;
%"RES"
"2","(-3950,4425)","2","mstr_discrete","I27";
;
CDS_SEC"1"
$SEC"1"
CDS_LOCATION"R3W6"
CDS_LIB"mstr_discrete"
ROOM"SB_SPI"
BOM_COST"MIO_BIOS_MEM"
NO_XNET_CONNECTION"1"
LOCATION"R3W6"
VALUE"4.75K"
MATERIAL"CHIP"
WATTAGE"1/16W"
PACK_TYPE"0402"
TOLERANCE"1%"
PART_NUMBER"G21796-072";
"A"
$PN"1"8;
"B"
$PN"2"12;
%"NPN"
"1","(-4600,3975)","0","mstr_discrete","I29";
;
CDS_SEC"1"
$SEC"1"
CDS_LOCATION"Q9W2"
CDS_LIB"mstr_discrete"
ROOM"SB"
VALUE"MMBT3904"
PART_NUMBER"C52245-001"
MATERIAL"IC"
PACK_TYPE"SM"
LOCATION"Q9W2";
"C"
$PN"3"13;
"E"
$PN"2"1;
"B"
$PN"1"17;
%"GND"
"1","(-6925,1625)","0","mstr_symbols","I3";
;
VOLTAGE"0.0V"
BODY_TYPE"PLUMBING"
CDS_LIB"mstr_symbols"
SIZE"1B"
HDL_POWER"GND";
"A\NAC"9;
%"FET_N"
"8","(-5875,2250)","0","mstr_discrete","I30";
;
CDS_SEC"1"
$SEC"1"
CDS_LOCATION"Q9W1"
ROOM"HOT_SWAP"
PACK_TYPE"SOT23LF"
CDS_LIB"mstr_discrete"
VALUE"2N7002"
MATERIAL"FET"
LOCATION"Q9W1"
PART_NUMBER"C79254-001";
"GATE"
$PN"1"18;
"DRN"
$PN"3"14;
"SRC"
$PN"2"2;
%"47KR2F-GP"
"1","(-5375,3975)","1","w_hdl","I31";
;
CDS_SEC"1"
$SEC"1"
CDS_LOCATION"R3W4"
PACK_TYPE"RCL_GP"
PART_NUMBER"64.47025.6DL"
CDS_LIB"w_hdl"
CDS_LMAN_SYM_OUTLINE"-50,75,50,-75"
LOCATION"R3W4"
VALUE"47KR2F-GP";
"2"
$PN"2"17;
"1"
$PN"1"14;
%"CAP"
"1","(-6800,2150)","1","mstr_discrete","I32";
;
CDS_SEC"1"
$SEC"1"
CDS_LOCATION"C8W1"
ROOM"NIC_SPRV"
BOM_COST"NT_GBE_BASE"
CDS_LIB"mstr_discrete"
VALUE"10UF"
MATERIAL"X6S"
PART_NUMBER"E15431-002"
PACK_TYPE"0603"
TOLERANCE"20%"
VOLTAGE"6.3V"
LOCATION"C8W1";
"A"
$PN"1"15;
"B"
$PN"2"18;
%"82K5R2F-GP"
"1","(-4550,4400)","0","w_hdl","I33";
;
CDS_SEC"1"
$SEC"1"
CDS_LOCATION"R3W5"
CDS_LMAN_SYM_OUTLINE"-50,75,50,-75"
CDS_LIB"w_hdl"
PART_NUMBER"64.82525.6DL"
PACK_TYPE"SMD-RG"
VALUE"82K5R2F-GP"
LOCATION"R3W5";
"2"
$PN"2"13;
"1"
$PN"1"8;
%"GND"
"1","(-4225,1975)","0","mstr_symbols","I6";
;
VOLTAGE"0.0V"
BODY_TYPE"PLUMBING"
SIZE"1B"
HDL_POWER"GND"
CDS_LIB"mstr_symbols";
"A\NAC"10;
%"RES"
"2","(-4225,2300)","0","mstr_discrete","I7";
;
CDS_SEC"1"
$SEC"1"
CDS_LOCATION"R3W9"
ROOM"M_2"
BOM_COST"ST_FLASH"
CDS_LIB"mstr_discrete"
PACK_TYPE"0402"
MATERIAL"CHIP"
PART_NUMBER"G21796-016"
WATTAGE"1/16W"
TOLERANCE"1%"
VALUE"10.0K"
LOCATION"R3W9";
"A"
$PN"1"19;
"B"
$PN"2"10;
%"RES"
"2","(-4225,2775)","2","mstr_discrete","I8";
;
CDS_SEC"1"
$SEC"1"
CDS_LOCATION"R3W7"
CDS_LIB"mstr_discrete"
NO_XNET_CONNECTION"1"
BOM_COST"MIO_BIOS_MEM"
ROOM"SB_SPI"
PART_NUMBER"G21796-072"
WATTAGE"1/16W"
PACK_TYPE"0402"
VALUE"4.75K"
TOLERANCE"1%"
MATERIAL"CHIP"
LOCATION"R3W7";
"A"
$PN"1"11;
"B"
$PN"2"19;
%"P3V3_STBY"
"1","(-4225,3100)","0","mstr_symbols","I9";
;
VOLTAGE"3.3V"
CDS_LIB"mstr_symbols"
SIZE"1B"
BODY_TYPE"PLUMBING"
HDL_POWER"P3V3_STBY";
"G\NAC"11;
END.
